# BASEBOARD_FAB2 (Tioga Pass) — schematic parts with pin connectivity, parts 805–972 of 4751; source: Cadence DE-HDL packaged netlist (pstxprt.dat, pstxnet.dat, pstchip.dat)

C4B11  CAP  10UF 16V 10% X7R  pkg 0805  page 197 : 1 = P12V_NVDIMM_DEF ; 2 = GND
C4B12  CAP_A  0.01UF 25V 10% X7R  pkg 0402V  page 49 : 1 = M_D_VREF ; 2 = GND
C4B13  CAPP  470UF 16V 20% ALUM  pkg 4040LF  page 195 : 1 = P12V_STBY ; 2 = GND
C4B14  CAPP  68UF 16V 20% TANT  pkg 3018  page 195 : 1 = P12V_STBY ; 2 = GND
C4B15  CAP  0.1UF 25V 10% X7R  pkg 0603LF  page 234 : 1 = VR_PVPP_KLM_PHASE ; 2 = VR_PVPP_KLM_BOOT_R
C4C1  CAPP  470UF 2.5V 20% ALUM  pkg 3018  page 193 : 1 = PVCCIOMCP_CPU1 ; 2 = GND
C4C3  CAP_A  1.0UF 6.3V 10% X6S  pkg 0402V  page 96 : 1 = P3V3_STBY ; 2 = GND
C4C4  SC1U10V2KX-4-GP  10%  pkg SMD-BCG6  page 205 : 1 = P5V_STBY ; 2 = GND
C4C5  CAP  0.22UF 16V 10% X7R  pkg 0402  page 205 : 1 = P5V_STBY ; 2 = GND
C4C6  CAP  1.0UF 16V 10% X6S  pkg 0402  page 205 : 1 = VR_PVSA_CPU0_VCIN ; 2 = GND
C4C8  CAP  0.220UF 16V 10% X7R  pkg 0402  page 205 : 1 = VR_PVSA_CPU0_BOOT ; 2 = VR_PVSA_CPU0_PHASE
C4C9  CAP  1.0UF 16V 10% X6S  pkg 0402  page 205 : 1 = VR_FET_SW_P12V_STBY_PVCCIN_CPU0 ; 2 = GND
C4C10  CAP_A  0.1UF 16V 10% X7R  pkg 0402V  page 205 : 1 = VR_FET_SW_P12V_STBY_PVCCIN_CPU0 ; 2 = GND
C4C11  CAP_A  22.0UF 4V 20% X6S  pkg 0603V  page 205 : 1 = PVSA_CPU0 ; 2 = GND
C4C12  CAPP  270UF 16V 20% OSCON  pkg 2626  page 204 : 1 = VR_FET_SW_P12V_STBY_PVCCIN_CPU0 ; 2 = GND
C4C14  SC1U10V2KX-4-GP  10%  pkg SMD-BCG6  page 204 : 1 = P5V_STBY ; 2 = GND
C4C17  CAP  0.220UF 16V 10% X7R  pkg 0402  page 204 : 1 = VR_PVCCIN_CPU0_PH5_BOOT ; 2 = VR_PVCCIN_CPU0_PH5_PHASE
C4C18  CAP  1.0UF 16V 10% X6S  pkg 0402  page 204 : 1 = VR_FET_SW_P12V_STBY_PVCCIN_CPU0 ; 2 = GND
C4C19  CAP_A  0.1UF 16V 10% X7R  pkg 0402V  page 204 : 1 = VR_FET_SW_P12V_STBY_PVCCIN_CPU0 ; 2 = GND
C4D2  CAPP  270UF 16V 20% OSCON  pkg 2626  page 204 : 1 = VR_FET_SW_P12V_STBY_PVCCIN_CPU0 ; 2 = GND
C4D4  CAP_A  22.0UF 4V 20% X6S  pkg 0603V  page 203 : 1 = PVCCIN_CPU0 ; 2 = GND
C4D5  CAP  0.22UF 16V 10% X7R  pkg 0402  page 203 : 1 = P5V_STBY ; 2 = GND
C4D6  SC1U10V2KX-4-GP  10%  pkg SMD-BCG6  page 203 : 1 = P5V_STBY ; 2 = GND
C4D7  CAP  1.0UF 16V 10% X6S  pkg 0402  page 203 : 1 = VR_PVCCIN_CPU0_PH4_VCIN ; 2 = GND
C4D9  CAP  0.220UF 16V 10% X7R  pkg 0402  page 203 : 1 = VR_PVCCIN_CPU0_PH4_BOOT ; 2 = VR_PVCCIN_CPU0_PH4_PHASE
C4D10  CAP  1.0UF 16V 10% X6S  pkg 0402  page 203 : 1 = VR_FET_SW_P12V_STBY_PVCCIN_CPU0 ; 2 = GND
C4D11  CAP_A  0.1UF 16V 10% X7R  pkg 0402V  page 203 : 1 = VR_FET_SW_P12V_STBY_PVCCIN_CPU0 ; 2 = GND
C4D12  CAP_A  22.0UF 4V 20% X6S  pkg 0603V  page 204 : 1 = PVCCIN_CPU0 ; 2 = GND
C4D13  CAP  0.22UF 16V 10% X7R  pkg 0402  page 203 : 1 = P5V_STBY ; 2 = GND
C4D14  SC1U10V2KX-4-GP  10%  pkg SMD-BCG6  page 203 : 1 = P5V_STBY ; 2 = GND
C4D15  CAP_A  1.0UF 6.3V 10% X6S  pkg 0402V  page 201 : 1 = VR_PVCCIN_CPU0_VDD ; 2 = GND
C4D16  CAP  1.0UF 16V 10% X6S  pkg 0402  page 203 : 1 = VR_PVCCIN_CPU0_PH3_VCIN ; 2 = GND
C4D17  CAP  220PF 50V 10% X7R  pkg 0402LF  page 201 : 1 = A_TSENSE_PVCCIN_CPU0 ; 2 = GND
C4D18  CAP  220PF 50V 10% X7R  pkg 0402LF  page 201 : 1 = A_TSENSE_PVSA_CPU0 ; 2 = GND
C4D19  CAP_A  0.1UF 16V 10% X7R  pkg 0402V  page 201 : 1 = VR_PVCCIN_CPU0_VDD ; 2 = GND
C4D20  CAP_A  0.1UF 16V 10% X7R  pkg 0402V  page 201 : 1 = VR_PVCCIN_CPU0_AVINSEN ; 2 = GND
C4D22  CAP_A  0.1UF 16V 10% X7R  pkg 0402V  page 102 : 1 = P3V3_DB1200_R ; 2 = GND
C4D23  CAP_A  1.0UF 6.3V 10% X6S  pkg 0402V  page 102 : 1 = P3V3_DB1200_A ; 2 = GND
C4D24  CAP_A  0.1UF 16V 10% X7R  pkg 0402V  page 102 : 1 = P3V3_DB1200_A ; 2 = GND
C4D25  CAP_A  1.0UF 6.3V 10% X6S  pkg 0402V  page 201 : 1 = VR_PVCCIN_CPU0_VD12 ; 2 = GND
C4D26  CAP_A  0.1UF 16V 10% X7R  pkg 0402V  page 201 : 1 = VR_PVCCIN_CPU0_VD12 ; 2 = GND
C4D27  CAP_A  1.0UF 6.3V 10% X6S  pkg 0402V  page 102 : 1 = P3V3_DB1200_R ; 2 = GND
C4D28  CAP  0.220UF 16V 10% X7R  pkg 0402  page 203 : 1 = VR_PVCCIN_CPU0_PH3_BOOT ; 2 = VR_PVCCIN_CPU0_PH3_PHASE
C4D29  CAP  220PF 50V 10% X7R  pkg 0402LF  page 201 : 1 = VSENSE_PVSA_CPU0_BVSP ; 2 = VSENSE_PVSA_CPU0_N
C4D30  CAP  1.0UF 16V 10% X6S  pkg 0402  page 203 : 1 = VR_FET_SW_P12V_STBY_PVCCIN_CPU0 ; 2 = GND
C4D31  CAP_A  1.0UF 6.3V 10% X6S  pkg 0402V  page 213 : 1 = VR_PVCCIO_CPU1_VD12 ; 2 = GND
C4D32  CAP_A  0.1UF 16V 10% X7R  pkg 0402V  page 213 : 1 = VR_PVCCIO_CPU1_VD12 ; 2 = GND
C4D33  CAP  1000PF 50V 10% X7R  pkg 0402LF  page 213 : 1 = PWRGD_PVCCIO_CPU1_R ; 2 = GND
C4D34  CAP_A  22.0UF 4V 20% X6S  pkg 0603V  page 203 : 1 = PVCCIN_CPU0 ; 2 = GND
C4D35  CAP_A  0.1UF 16V 10% X7R  pkg 0402V  page 203 : 1 = VR_FET_SW_P12V_STBY_PVCCIN_CPU0 ; 2 = GND
C4D36  CAP_A  1.0UF 6.3V 10% X6S  pkg 0402V  page 213 : 1 = VR_PVCCIO_CPU1_VDD ; 2 = GND
C4D38  CAP_A  0.1UF 16V 10% X7R  pkg 0402V  page 213 : 1 = VR_PVCCIO_CPU1_VDD ; 2 = GND
C4D40  CAP_A  0.1UF 16V 10% X7R  pkg 0402V  page 213 : 1 = VR_PVCCIO_CPU1_VINSEN ; 2 = GND
C4D42  CAP  1000PF 50V 10% X7R  pkg 0402LF  page 201 : 1 = VR_VRRDY_PVCCIN_CPU0 ; 2 = GND
C4D44  CAP  220PF 50V 10% X7R  pkg 0402LF  page 213 : 1 = VR_PVCCIO_CPU1_AVSP ; 2 = VSENSE_PVCCIO_CPU1_AVSN
C4D45  CAP  220PF 50V 10% X7R  pkg 0402LF  page 201 : 1 = VSENSE_PVCCIN_CPU0_AVSP ; 2 = VSENSE_PVCCIN_CPU0_N
C4D46  CAP  1.0UF 16V 10% X6S  pkg 0402  page 204 : 1 = VR_PVCCIN_CPU0_PH5_VCIN ; 2 = GND
C4D47  CAP  0.22UF 16V 10% X7R  pkg 0402  page 204 : 1 = P5V_STBY ; 2 = GND
C4D48  CAP  1.0UF 16V 10% X6S  pkg 0402  page 202 : 1 = VR_FET_SW_P12V_STBY_PVCCIN_CPU0 ; 2 = GND
C4D49  CAP_A  0.1UF 16V 10% X7R  pkg 0402V  page 202 : 1 = VR_FET_SW_P12V_STBY_PVCCIN_CPU0 ; 2 = GND
C4D50  CAP  0.220UF 16V 10% X7R  pkg 0402  page 202 : 1 = VR_PVCCIN_CPU0_PH2_BOOT ; 2 = VR_PVCCIN_CPU0_PH2_PHASE
C4E3  CAP_A  22.0UF 4V 20% X6S  pkg 0603V  page 202 : 1 = PVCCIN_CPU0 ; 2 = GND
C4E5  CAP  0.22UF 16V 10% X7R  pkg 0402  page 202 : 1 = P5V_STBY ; 2 = GND
C4E6  SC1U10V2KX-4-GP  10%  pkg SMD-BCG6  page 202 : 1 = P5V_STBY ; 2 = GND
C4E7  CAPP  470UF 2.5V 20% ALUM  pkg 3018  page 214 : 1 = PVCCIO_CPU1 ; 2 = GND
C4E8  SC22U16V5MX-4-GP  20%  pkg SMD-BCG5  page 214 : 1 = VR_FET_SW_P12V_STBY_PVCCIN_CPU0 ; 2 = GND
C4E9  SC22U16V5MX-4-GP  20%  pkg SMD-BCG5  page 214 : 1 = VR_FET_SW_P12V_STBY_PVCCIN_CPU0 ; 2 = GND
C4E10  CAP  1.0UF 16V 10% X6S  pkg 0402  page 202 : 1 = VR_PVCCIN_CPU0_PH1_VCIN ; 2 = GND
C4E11  CAP_A  22.0UF 4V 20% X6S  pkg 0603V  page 202 : 1 = PVCCIN_CPU0 ; 2 = GND
C4E13  CAP_A  0.1UF 16V 10% X7R  pkg 0402V  page 214 : 1 = VR_FET_SW_P12V_STBY_PVCCIN_CPU0 ; 2 = GND
C4E14  SC22U16V5MX-4-GP  20%  pkg SMD-BCG5  page 214 : 1 = VR_FET_SW_P12V_STBY_PVCCIN_CPU0 ; 2 = GND
C4E15  CAP  1.0UF 16V 10% X6S  pkg 0402  page 214 : 1 = VR_FET_SW_P12V_STBY_PVCCIN_CPU0 ; 2 = GND
C4E16  CAPP  270UF 16V 20% OSCON  pkg 2626  page 204 : 1 = VR_FET_SW_P12V_STBY_PVCCIN_CPU0 ; 2 = GND
C4E17  CAP  0.220UF 16V 10% X7R  pkg 0402  page 202 : 1 = VR_PVCCIN_CPU0_PH1_BOOT ; 2 = VR_PVCCIN_CPU0_PH1_PHASE
C4E18  CAP  0.220UF 16V 10% X7R  pkg 0402  page 214 : 1 = VR_PVCCIO_CPU1_PH1_BOOT ; 2 = VR_PVCCIO_CPU1_PH1_PHASE
C4E19  CAP  1.0UF 16V 10% X6S  pkg 0402  page 202 : 1 = VR_FET_SW_P12V_STBY_PVCCIN_CPU0 ; 2 = GND
C4E20  CAP_A  0.1UF 16V 10% X7R  pkg 0402V  page 202 : 1 = VR_FET_SW_P12V_STBY_PVCCIN_CPU0 ; 2 = GND
C4E22  CAP  1.0UF 16V 10% X6S  pkg 0402  page 214 : 1 = VR_PVCCIO_CPU1_PH1_VCIN ; 2 = GND
C4E23  CAP  0.22UF 16V 10% X7R  pkg 0402  page 214 : 1 = P5V_STBY ; 2 = GND
C4E24  CAPP  470UF 2.5V 20% ALUM  pkg 3018  page 193 : 1 = PVCCMCP_CPU1 ; 2 = GND
C4E25  SC1U10V2KX-4-GP  10%  pkg SMD-BCG6  page 202 : 1 = P5V_STBY ; 2 = GND
C4E26  CAP  1.0UF 16V 10% X6S  pkg 0402  page 202 : 1 = VR_PVCCIN_CPU0_PH2_VCIN ; 2 = GND
C4E27  CAP  0.22UF 16V 10% X7R  pkg 0402  page 202 : 1 = P5V_STBY ; 2 = GND
C4E28  SC1U10V2KX-4-GP  10%  pkg SMD-BCG6  page 214 : 1 = P5V_STBY ; 2 = GND
C4E29  CAPP  470UF 2.5V 20% ALUM  pkg 3018  page 193 : 1 = PVCCMCP_CPU1 ; 2 = GND
C4F1  CAP_A  1.0UF 6.3V 10% X6S  pkg 0402V  page 193 : 1 = P1V8_MCP_CPU1 ; 2 = GND
C4F2  CAP_A  47UF 4V 20% X5R  pkg 0603V  page 193 : 1 = P1V8_MCP_CPU1 ; 2 = GND
C4F3  CAP_A  1.0UF 6.3V 10% X6S  pkg 0402V  page 193 : 1 = P1V8_MCP_CPU1 ; 2 = GND
C4F4  CAPP  68UF 16V 20% TANT  pkg 3018  page 195 : 1 = P12V_STBY ; 2 = GND
C4F5  CAPP  68UF 16V 20% TANT  pkg 3018  page 195 : 1 = P12V_STBY ; 2 = GND
C4F6  CAPP  470UF 16V 20% ALUM  pkg 4040LF  page 195 : 1 = P12V_STBY ; 2 = GND
C4F7  CAPP  330UF 6.3V 20% POSCAP  pkg 7343LF  page 233 : 1 = PVPP_GHJ ; 2 = GND
C4F9  CAP_A  0.01UF 25V 10% X7R  pkg 0402V  page 98 : 1 = M_A_CPU_VREF ; 2 = GND
C4F10  CAP_A  0.01UF 25V 10% X7R  pkg 0402V  page 43 : 1 = M_A_VREF ; 2 = GND
C4F11  CAPP  220UF 4V 20% POSCAP  pkg 7343  page 233 : 1 = PVPP_GHJ ; 2 = GND
C4F12  CAP  3300PF 50V 10% EMPTY  pkg 0402LF  page 233 : 1 = VR_PVPP_GHJ_PHASE ; 2 = VR_PVPP_GHJ_SNUB
C4G1  CAP_A  0.01UF 25V 10% X7R  pkg 0402V  page 98 : 1 = M_B_CPU_VREF ; 2 = GND
C4G2  CAP  10UF 16V 10% X6S  pkg 0805  page 233 : 1 = VR_FET_SW_P12V_STBY_PVPP_GHJ ; 2 = GND
C4G3  CAP_A  0.01UF 25V 10% X7R  pkg 0402V  page 45 : 1 = M_B_VREF ; 2 = GND
C4G4  CAP  1.0UF 16V 10% X6S  pkg 0402  page 233 : 1 = VR_FET_SW_P12V_STBY_PVPP_GHJ ; 2 = GND
C4G5  SC22U16V5MX-4-GP  20%  pkg SMD-BCG5  page 233 : 1 = VR_FET_SW_P12V_STBY_PVPP_GHJ ; 2 = GND
C4G6  CAP  100.0PF 50V 5% COG  pkg 0402LF  page 233 : 1 = VR_FB_PVPP_GHJ ; 2 = VR_COMP_PVPP_GHJ_3
C4G7  CAP  1000PF 50V 10% EMPTY  pkg 0402LF  page 233 : 1 = FM_PVPP_CPU1_EN ; 2 = AGND_PVPP_GHJ
C4G8  CAP  0.027UF 16V 10% X7R  pkg 0402  page 233 : 1 = VR_PVPP_GHJ_SS ; 2 = AGND_PVPP_GHJ
C4G9  CAP  1000PF 50V 10% X7R  pkg 0402LF  page 233 : 1 = PWRGD_PVPP_GHJ_R ; 2 = GND
C4G10  CAP  2200PF 50V 10% X7R  pkg 0402LF  page 233 : 1 = VR_COMP_RC_PVPP_GHJ ; 2 = VR_COMP_PVPP_GHJ_3
C4G11  CAP  2200PF 50V 10% X7R  pkg 0402LF  page 233 : 1 = VR_COMP_PVPP_GHJ ; 2 = VR_FB_PVPP_GHJ
C4G12  CAP  1000PF 50V 10% EMPTY  pkg 0402LF  page 229 : 1 = FM_PVTT_GHJ_EN_R ; 2 = GND
C4G13  CAP  1000PF 50V 10% X7R  pkg 0402LF  page 229 : 1 = PWRGD_PVTT_GHJ_CPU1_R ; 2 = GND
C4G14  CAP  1000PF 50V 10% X7R  pkg 0402LF  page 221 : 1 = PWRGD_PVTT_ABC_CPU0_R ; 2 = GND
C4G15  CAP  1.0UF 16V 10% X6S  pkg 0402  page 221 : 1 = VR_PVTT_ABC_BIAS ; 2 = GND
C4G16  CAP  1.0UF 16V 10% X6S  pkg 0402  page 221 : 1 = VR_PVTT_ABC_VREF ; 2 = GND
C4G17  CAP_A  0.01UF 25V 10% X7R  pkg 0402V  page 98 : 1 = M_C_CPU_VREF ; 2 = GND
C4G18  CAP  1.0UF 16V 10% X6S  pkg 0402  page 229 : 1 = VR_PVTT_GHJ_BIAS ; 2 = GND
C4G19  CAP_A  0.01UF 25V 10% X7R  pkg 0402V  page 47 : 1 = M_C_VREF ; 2 = GND
C4G20  CAP  22UF 4V 20% X6S  pkg 0805LF  page 229 : 1 = PVTT_GHJ ; 2 = GND
C4G21  CAP  1.0UF 16V 10% X6S  pkg 0402  page 229 : 1 = VR_PVTT_GHJ_VREF ; 2 = GND
C4G22  CAP_A  0.1UF 16V 10% X7R  pkg 0402V  page 99 : 1 = PVCCIO_CPU1 ; 2 = GND
C4G23  CAP  1000PF 50V 10% EMPTY  pkg 0402LF  page 221 : 1 = FM_PVTT_ABC_EN_R ; 2 = GND
C4G24  CAP  22UF 4V 20% X6S  pkg 0805LF  page 221 : 1 = PVTT_ABC ; 2 = GND
C4G25  CAP_A  0.1UF 16V 10% X7R  pkg 0402V  page 99 : 1 = PVPP_GHJ ; 2 = GND
C4G26  CAP  0.1UF 25V 10% X7R  pkg 0603LF  page 233 : 1 = VR_PVPP_GHJ_PHASE ; 2 = VR_PVPP_GHJ_BOOT_R
C4L1  CAP  10UF 4V 20% X6S  pkg 0603LF  page 232 : 1 = PVPP_DEF ; 2 = GND
C4L2  CAP  10UF 4V 20% X6S  pkg 0603LF  page 232 : 1 = PVPP_DEF ; 2 = GND
C4L3  CAP  10UF 4V 20% X6S  pkg 0603LF  page 232 : 1 = PVPP_DEF ; 2 = GND
C4L4  CAP  10UF 4V 20% X6S  pkg 0603LF  page 232 : 1 = PVPP_DEF ; 2 = GND
C4L5  CAPP  470UF 2.5V 20% ALUM  pkg 3018  page 220 : 1 = PVDDQ_DEF ; 2 = GND
C4M1  CAPP  220UF 4V 20% POSCAP  pkg 7343  page 232 : 1 = PVPP_DEF ; 2 = GND
C4M2  CAP_A  47UF 4V 20% X5R  pkg 0603V  page 220 : 1 = PVDDQ_DEF ; 2 = GND
C4M3  CAP  10UF 4V 20% X6S  pkg 0603LF  page 232 : 1 = PVPP_DEF ; 2 = GND
C4M4  CAP  10UF 4V 20% X6S  pkg 0603LF  page 232 : 1 = PVPP_DEF ; 2 = GND
C4M5  CAP_A  47UF 4V 20% X5R  pkg 0603V  page 220 : 1 = PVDDQ_DEF ; 2 = GND
C4M6  CAPP  68UF 16V 20% TANT  pkg 3018  page 195 : 1 = P12V_STBY ; 2 = GND
C4M7  CAPP  68UF 16V 20% TANT  pkg 3018  page 195 : 1 = P12V_STBY ; 2 = GND
C4P1  CAP  47UF 4V 20% X6S  pkg 0805  page 42 : 1 = PVCCIO_CPU0 ; 2 = GND
C4P2  CAP  100UF 4V 20% X5R  pkg 0805  page 42 : 1 = PVCCMCP_CPU0 ; 2 = GND
C4P3  CAP  100UF 4V 20% X5R  pkg 0805  page 42 : 1 = PVCCMCP_CPU0 ; 2 = GND
C4P4  CAP  100UF 4V 20% X5R  pkg 0805  page 42 : 1 = PVCCMCP_CPU0 ; 2 = GND
C4P5  CAP  100UF 4V 20% X5R  pkg 0805  page 42 : 1 = PVCCMCP_CPU0 ; 2 = GND
C4P6  CAP_A  22.0UF 4V 20% X6S  pkg 0603V  page 42 : 1 = PVCCIO_CPU0 ; 2 = GND
C4P7  CAP  100UF 4V 20% X5R  pkg 0805  page 42 : 1 = PVCCMCP_CPU0 ; 2 = GND
C4P8  CAP_A  22.0UF 4V 20% X6S  pkg 0603V  page 42 : 1 = PVCCIO_CPU0 ; 2 = GND
C4P9  CAP  47UF 4V 20% X6S  pkg 0805  page 42 : 1 = PVCCIO_CPU0 ; 2 = GND
C4P10  CAP  47UF 4V 20% X6S  pkg 0805  page 42 : 1 = PVCCIO_CPU0 ; 2 = GND
C4R1  CAPP  470UF 2.5V 20% ALUM  pkg 3018  page 194 : 1 = PVCCMCP_CPU0 ; 2 = GND
C4R2  CAP_A  0.1UF 16V 10% X7R  pkg 0402V  page 113 : 1 = JTAG_MCP_CPU0_TDI_R ; 2 = GND
C4T1  CAP_A  1.0UF 6.3V 10% X6S  pkg 0402V  page 194 : 1 = P1V8_MCP_CPU0 ; 2 = GND
C4T2  CAP_A  1.0UF 6.3V 10% X6S  pkg 0402V  page 194 : 1 = P1V8_MCP_CPU0 ; 2 = GND
C4T3  CAPP  220UF 4V 20% POSCAP  pkg 7343  page 231 : 1 = PVPP_ABC ; 2 = GND
C4T4  CAP  100UF 4V 20% X5R  pkg 0805  page 217 : 1 = PVDDQ_ABC ; 2 = GND
C4T5  CAP  10UF 4V 20% X6S  pkg 0603LF  page 231 : 1 = PVPP_ABC ; 2 = GND
C4T6  CAP  10UF 4V 20% X6S  pkg 0603LF  page 231 : 1 = PVPP_ABC ; 2 = GND
C4U1  CAP  10UF 4V 20% X6S  pkg 0603LF  page 231 : 1 = PVPP_ABC ; 2 = GND
C4U2  CAP  10UF 4V 20% X6S  pkg 0603LF  page 231 : 1 = PVPP_ABC ; 2 = GND
C4U3  CAP  10UF 4V 20% X6S  pkg 0603LF  page 231 : 1 = PVPP_ABC ; 2 = GND
C4U4  CAP  10UF 4V 20% X6S  pkg 0603LF  page 231 : 1 = PVPP_ABC ; 2 = GND
C4W1  CAP  220PF 50V 10% X7R  pkg 0402LF  page 211 : 1 = A_TSENSE_PVCCIO_CPU0 ; 2 = GND
C4W2  CAP  220PF 50V 10% X7R  pkg 0402LF  page 213 : 1 = A_TSENSE_PVCCIO_CPU1 ; 2 = GND
C4W3  CAP  220PF 50V 10% X7R  pkg 0402LF  page 235 : 1 = A_TSENSE_PVNN_PCH_TMON ; 2 = GND
C4W4  CAP  220PF 50V 10% X7R  pkg 0402LF  page 235 : 1 = A_TSENSE_P1V05_PCH_STBY_TMON ; 2 = GND
C4W5  CAP  100UF 4V 20% X5R  pkg 0805  page 222 : 1 = PVTT_DEF ; 2 = GND
C5A1  CAP_A  47UF 4V 20% X5R  pkg 0603V  page 220 : 1 = PVDDQ_DEF ; 2 = GND
C5A2  CAP_A  47UF 4V 20% X5R  pkg 0603V  page 220 : 1 = PVDDQ_DEF ; 2 = GND
C5A3  CAP_A  47UF 4V 20% X5R  pkg 0603V  page 220 : 1 = PVDDQ_DEF ; 2 = GND
C5A4  CAP_A  47UF 4V 20% X5R  pkg 0603V  page 220 : 1 = PVDDQ_DEF ; 2 = GND
C5A5  CAP_A  47UF 4V 20% X5R  pkg 0603V  page 220 : 1 = PVDDQ_DEF ; 2 = GND
C5A6  CAP_A  47UF 4V 20% X5R  pkg 0603V  page 220 : 1 = PVDDQ_DEF ; 2 = GND
C5A7  CAP_A  47UF 4V 20% X5R  pkg 0603V  page 220 : 1 = PVDDQ_DEF ; 2 = GND
